(kicad_pcb
	(version 20260206)
	(generator "pcbnew")
	(generator_version "10.0")
	(general
		(thickness 1.6)
		(legacy_teardrops no)
	)
	(paper "A4")
	(title_block
		(title "04192023_DAF0TMB3IC0_F0TG_MB_C_brd_V02_OCP.brd")
		(comment 1 "Grand Teton / footprints 7582-7588 of 8354")
	)
	(layers
		(0 "F.Cu" signal "TOP")
		(4 "In1.Cu" signal "GND")
		(6 "In2.Cu" signal "IN1")
		(8 "In3.Cu" signal "GND1")
		(10 "In4.Cu" signal "IN2")
		(12 "In5.Cu" signal "GND2")
		(14 "In6.Cu" signal "IN3")
		(16 "In7.Cu" signal "GND3")
		(18 "In8.Cu" signal "VCC")
		(20 "In9.Cu" signal "VCC1")
		(22 "In10.Cu" signal "GND4")
		(24 "In11.Cu" signal "IN4")
		(26 "In12.Cu" signal "GND5")
		(28 "In13.Cu" signal "IN5")
		(30 "In14.Cu" signal "GND6")
		(32 "In15.Cu" signal "IN6")
		(34 "In16.Cu" signal "GND7")
		(2 "B.Cu" signal "BOTTOM")
		(9 "F.Adhes" user "F.Adhesive")
		(11 "B.Adhes" user "B.Adhesive")
		(13 "F.Paste" user "Package Geometry/Pastemask Top")
		(15 "B.Paste" user "Package Geometry/Pastemask Bottom")
		(5 "F.SilkS" user "Ref Des/Silkscreen Top")
		(7 "B.SilkS" user "Ref Des/Silkscreen Bottom")
		(1 "F.Mask" user "Board Geometry/Soldermask Top")
		(3 "B.Mask" user "Board Geometry/Soldermask Bottom")
		(17 "Dwgs.User" user "User.Drawings")
		(19 "Cmts.User" user "User.Comments")
		(21 "Eco1.User" user "User.Eco1")
		(23 "Eco2.User" user "User.Eco2")
		(25 "Edge.Cuts" user "Board Geometry/Outline")
		(27 "Margin" user)
		(31 "F.CrtYd" user "Package Geometry/Place Bound Top")
		(29 "B.CrtYd" user "Package Geometry/Place Bound Bottom")
		(35 "F.Fab" user "Ref Des/Assembly Top")
		(33 "B.Fab" user "Ref Des/Assembly Bottom")
	)
	(footprint ""
		(layer "B.Cu")
		(at 108.933996 -26.952448 90)
		(property "Reference" "C6097"
			(at 0 0 90)
			(layer "B.SilkS")
			(hide yes)
			(effects
				(font
					(size 1.27 1.27)
				)
				(justify mirror)
			)
		)
		(property "Value" ""
			(at 0 0 90)
			(layer "B.Fab")
			(effects
				(font
					(size 1.27 1.27)
				)
				(justify mirror)
			)
		)
		(duplicate_pad_numbers_are_jumpers no)
		(fp_line
			(start 0.7874 -0.4064)
			(end -0.7874 -0.4064)
			(stroke
				(width 0.1524)
				(type default)
			)
			(layer "B.SilkS")
		)
		(fp_line
			(start -0.7874 -0.4064)
			(end -0.7874 0.4064)
			(stroke
				(width 0.1524)
				(type default)
			)
			(layer "B.SilkS")
		)
		(fp_line
			(start 0.7874 0.4064)
			(end 0.7874 -0.4064)
			(stroke
				(width 0.1524)
				(type default)
			)
			(layer "B.SilkS")
		)
		(fp_line
			(start -0.7874 0.4064)
			(end 0.7874 0.4064)
			(stroke
				(width 0.1524)
				(type default)
			)
			(layer "B.SilkS")
		)
		(fp_line
			(start 0.67945 -0.305054)
			(end 0.12065 -0.305054)
			(stroke
				(width 0.1)
				(type default)
			)
			(layer "B.Fab")
		)
		(fp_line
			(start 0.12065 -0.305054)
			(end 0.12065 -0.2794)
			(stroke
				(width 0.1)
				(type default)
			)
			(layer "B.Fab")
		)
		(fp_line
			(start -0.12065 -0.3048)
			(end -0.67945 -0.3048)
			(stroke
				(width 0.1)
				(type default)
			)
			(layer "B.Fab")
		)
		(fp_line
			(start -0.67945 -0.3048)
			(end -0.67945 0.3048)
			(stroke
				(width 0.1)
				(type default)
			)
			(layer "B.Fab")
		)
		(fp_line
			(start 0.12065 -0.2794)
			(end -0.12065 -0.2794)
			(stroke
				(width 0.1)
				(type default)
			)
			(layer "B.Fab")
		)
		(fp_line
			(start -0.12065 -0.2794)
			(end -0.12065 -0.3048)
			(stroke
				(width 0.1)
				(type default)
			)
			(layer "B.Fab")
		)
		(fp_line
			(start 0.12065 0.2794)
			(end 0.12065 0.3048)
			(stroke
				(width 0.1)
				(type default)
			)
			(layer "B.Fab")
		)
		(fp_line
			(start -0.120396 0.2794)
			(end 0.12065 0.2794)
			(stroke
				(width 0.1)
				(type default)
			)
			(layer "B.Fab")
		)
		(fp_line
			(start 0.67945 0.3048)
			(end 0.67945 -0.305054)
			(stroke
				(width 0.1)
				(type default)
			)
			(layer "B.Fab")
		)
		(fp_line
			(start 0.12065 0.3048)
			(end 0.67945 0.3048)
			(stroke
				(width 0.1)
				(type default)
			)
			(layer "B.Fab")
		)
		(fp_line
			(start -0.120396 0.3048)
			(end -0.120396 0.2794)
			(stroke
				(width 0.1)
				(type default)
			)
			(layer "B.Fab")
		)
		(fp_line
			(start -0.67945 0.3048)
			(end -0.120396 0.3048)
			(stroke
				(width 0.1)
				(type default)
			)
			(layer "B.Fab")
		)
		(pad "1" smd circle
			(at 0.40005 0 270)
			(size 0 0)
			(layers "B.Cu" "B.Mask" "B.Paste")
			(net "P3V3_AUX_CPU0_USB2_AVDD33")
		)
		(pad "2" smd circle
			(at -0.40005 0 270)
			(size 0 0)
			(layers "B.Cu" "B.Mask" "B.Paste")
			(net "GND")
		)
	)
	(footprint ""
		(layer "B.Cu")
		(at 429.103282 -438.192672 -90)
		(property "Reference" "C7"
			(at 0 0 90)
			(layer "B.SilkS")
			(hide yes)
			(effects
				(font
					(size 1.27 1.27)
				)
				(justify mirror)
			)
		)
		(property "Value" ""
			(at 0 0 90)
			(layer "B.Fab")
			(effects
				(font
					(size 1.27 1.27)
				)
				(justify mirror)
			)
		)
		(duplicate_pad_numbers_are_jumpers no)
		(fp_line
			(start -0.7874 0.4064)
			(end 0.7874 0.4064)
			(stroke
				(width 0.1524)
				(type default)
			)
			(layer "B.SilkS")
		)
		(fp_line
			(start 0.7874 0.4064)
			(end 0.7874 -0.4064)
			(stroke
				(width 0.1524)
				(type default)
			)
			(layer "B.SilkS")
		)
		(fp_line
			(start -0.7874 -0.4064)
			(end -0.7874 0.4064)
			(stroke
				(width 0.1524)
				(type default)
			)
			(layer "B.SilkS")
		)
		(fp_line
			(start 0.7874 -0.4064)
			(end -0.7874 -0.4064)
			(stroke
				(width 0.1524)
				(type default)
			)
			(layer "B.SilkS")
		)
		(fp_line
			(start -0.67945 0.3048)
			(end -0.120396 0.3048)
			(stroke
				(width 0.1)
				(type default)
			)
			(layer "B.Fab")
		)
		(fp_line
			(start -0.120396 0.3048)
			(end -0.120396 0.2794)
			(stroke
				(width 0.1)
				(type default)
			)
			(layer "B.Fab")
		)
		(fp_line
			(start 0.12065 0.3048)
			(end 0.67945 0.3048)
			(stroke
				(width 0.1)
				(type default)
			)
			(layer "B.Fab")
		)
		(fp_line
			(start 0.67945 0.3048)
			(end 0.67945 -0.305054)
			(stroke
				(width 0.1)
				(type default)
			)
			(layer "B.Fab")
		)
		(fp_line
			(start -0.120396 0.2794)
			(end 0.12065 0.2794)
			(stroke
				(width 0.1)
				(type default)
			)
			(layer "B.Fab")
		)
		(fp_line
			(start 0.12065 0.2794)
			(end 0.12065 0.3048)
			(stroke
				(width 0.1)
				(type default)
			)
			(layer "B.Fab")
		)
		(fp_line
			(start -0.12065 -0.2794)
			(end -0.12065 -0.3048)
			(stroke
				(width 0.1)
				(type default)
			)
			(layer "B.Fab")
		)
		(fp_line
			(start 0.12065 -0.2794)
			(end -0.12065 -0.2794)
			(stroke
				(width 0.1)
				(type default)
			)
			(layer "B.Fab")
		)
		(fp_line
			(start -0.67945 -0.3048)
			(end -0.67945 0.3048)
			(stroke
				(width 0.1)
				(type default)
			)
			(layer "B.Fab")
		)
		(fp_line
			(start -0.12065 -0.3048)
			(end -0.67945 -0.3048)
			(stroke
				(width 0.1)
				(type default)
			)
			(layer "B.Fab")
		)
		(fp_line
			(start 0.12065 -0.305054)
			(end 0.12065 -0.2794)
			(stroke
				(width 0.1)
				(type default)
			)
			(layer "B.Fab")
		)
		(fp_line
			(start 0.67945 -0.305054)
			(end 0.12065 -0.305054)
			(stroke
				(width 0.1)
				(type default)
			)
			(layer "B.Fab")
		)
		(pad "1" smd circle
			(at 0.40005 0 90)
			(size 0 0)
			(layers "B.Cu" "B.Mask" "B.Paste")
			(net "GPU_3V3IO_RSVD3_ISO")
		)
		(pad "2" smd circle
			(at -0.40005 0 90)
			(size 0 0)
			(layers "B.Cu" "B.Mask" "B.Paste")
			(net "GND")
		)
	)
	(footprint ""
		(layer "B.Cu")
		(at 129.567686 -408.517344 90)
		(property "Reference" "C6733"
			(at 0 0 90)
			(layer "B.SilkS")
			(hide yes)
			(effects
				(font
					(size 1.27 1.27)
				)
				(justify mirror)
			)
		)
		(property "Value" ""
			(at 0 0 90)
			(layer "B.Fab")
			(effects
				(font
					(size 1.27 1.27)
				)
				(justify mirror)
			)
		)
		(duplicate_pad_numbers_are_jumpers no)
		(fp_line
			(start 0.299974 -0.150114)
			(end -0.299974 -0.150114)
			(stroke
				(width 0.1)
				(type default)
			)
			(layer "B.Fab")
		)
		(fp_line
			(start -0.299974 -0.150114)
			(end -0.299974 0.150114)
			(stroke
				(width 0.1)
				(type default)
			)
			(layer "B.Fab")
		)
		(fp_line
			(start 0.299974 0.150114)
			(end 0.299974 -0.150114)
			(stroke
				(width 0.1)
				(type default)
			)
			(layer "B.Fab")
		)
		(fp_line
			(start -0.299974 0.150114)
			(end 0.299974 0.150114)
			(stroke
				(width 0.1)
				(type default)
			)
			(layer "B.Fab")
		)
		(pad "1" smd rect
			(at 0.2667 0 270)
			(size 0.3048 0.381)
			(layers "B.Cu" "B.Mask" "B.Paste")
			(net "P5E_CPU1_P3_TX_BUF_C_DP<4>")
		)
		(pad "2" smd rect
			(at -0.2667 0 270)
			(size 0.3048 0.381)
			(layers "B.Cu" "B.Mask" "B.Paste")
			(net "P5E_CPU1_P3_TX_BUF_DP<4>")
		)
	)
	(footprint ""
		(layer "B.Cu")
		(at 397.788892 -201.308208)
		(property "Reference" "R589"
			(at 0 0 0)
			(layer "B.SilkS")
			(hide yes)
			(effects
				(font
					(size 1.27 1.27)
				)
				(justify mirror)
			)
		)
		(property "Value" ""
			(at 0 0 0)
			(layer "B.Fab")
			(effects
				(font
					(size 1.27 1.27)
				)
				(justify mirror)
			)
		)
		(duplicate_pad_numbers_are_jumpers no)
		(fp_line
			(start -0.7874 -0.4064)
			(end -0.7874 0.4064)
			(stroke
				(width 0.1524)
				(type default)
			)
			(layer "B.SilkS")
		)
		(fp_line
			(start -0.7874 0.4064)
			(end 0.7874 0.4064)
			(stroke
				(width 0.1524)
				(type default)
			)
			(layer "B.SilkS")
		)
		(fp_line
			(start 0.7874 -0.4064)
			(end -0.7874 -0.4064)
			(stroke
				(width 0.1524)
				(type default)
			)
			(layer "B.SilkS")
		)
		(fp_line
			(start 0.7874 0.4064)
			(end 0.7874 -0.4064)
			(stroke
				(width 0.1524)
				(type default)
			)
			(layer "B.SilkS")
		)
		(fp_line
			(start -0.67945 -0.3048)
			(end -0.67945 0.3048)
			(stroke
				(width 0.1)
				(type default)
			)
			(layer "B.Fab")
		)
		(fp_line
			(start -0.67945 0.3048)
			(end -0.120396 0.3048)
			(stroke
				(width 0.1)
				(type default)
			)
			(layer "B.Fab")
		)
		(fp_line
			(start -0.12065 -0.3048)
			(end -0.67945 -0.3048)
			(stroke
				(width 0.1)
				(type default)
			)
			(layer "B.Fab")
		)
		(fp_line
			(start -0.12065 -0.2794)
			(end -0.12065 -0.3048)
			(stroke
				(width 0.1)
				(type default)
			)
			(layer "B.Fab")
		)
		(fp_line
			(start -0.120396 0.2794)
			(end 0.12065 0.2794)
			(stroke
				(width 0.1)
				(type default)
			)
			(layer "B.Fab")
		)
		(fp_line
			(start -0.120396 0.3048)
			(end -0.120396 0.2794)
			(stroke
				(width 0.1)
				(type default)
			)
			(layer "B.Fab")
		)
		(fp_line
			(start 0.12065 -0.305054)
			(end 0.12065 -0.2794)
			(stroke
				(width 0.1)
				(type default)
			)
			(layer "B.Fab")
		)
		(fp_line
			(start 0.12065 -0.2794)
			(end -0.12065 -0.2794)
			(stroke
				(width 0.1)
				(type default)
			)
			(layer "B.Fab")
		)
		(fp_line
			(start 0.12065 0.2794)
			(end 0.12065 0.3048)
			(stroke
				(width 0.1)
				(type default)
			)
			(layer "B.Fab")
		)
		(fp_line
			(start 0.12065 0.3048)
			(end 0.67945 0.3048)
			(stroke
				(width 0.1)
				(type default)
			)
			(layer "B.Fab")
		)
		(fp_line
			(start 0.67945 -0.305054)
			(end 0.12065 -0.305054)
			(stroke
				(width 0.1)
				(type default)
			)
			(layer "B.Fab")
		)
		(fp_line
			(start 0.67945 0.3048)
			(end 0.67945 -0.305054)
			(stroke
				(width 0.1)
				(type default)
			)
			(layer "B.Fab")
		)
		(pad "1" smd circle
			(at 0.40005 0 180)
			(size 0 0)
			(layers "B.Cu" "B.Mask" "B.Paste")
			(net "SCM_USB_OC_BU_R_N")
		)
		(pad "2" smd circle
			(at -0.40005 0 180)
			(size 0 0)
			(layers "B.Cu" "B.Mask" "B.Paste")
			(net "SCM_USB_OC_BUF_N")
		)
	)
	(footprint ""
		(layer "B.Cu")
		(at 350.446086 -396.393162 -90)
		(property "Reference" "C627"
			(at 0 0 90)
			(layer "B.SilkS")
			(hide yes)
			(effects
				(font
					(size 1.27 1.27)
				)
				(justify mirror)
			)
		)
		(property "Value" ""
			(at 0 0 90)
			(layer "B.Fab")
			(effects
				(font
					(size 1.27 1.27)
				)
				(justify mirror)
			)
		)
		(duplicate_pad_numbers_are_jumpers no)
		(fp_line
			(start -0.299974 0.150114)
			(end 0.299974 0.150114)
			(stroke
				(width 0.1)
				(type default)
			)
			(layer "B.Fab")
		)
		(fp_line
			(start 0.299974 0.150114)
			(end 0.299974 -0.150114)
			(stroke
				(width 0.1)
				(type default)
			)
			(layer "B.Fab")
		)
		(fp_line
			(start -0.299974 -0.150114)
			(end -0.299974 0.150114)
			(stroke
				(width 0.1)
				(type default)
			)
			(layer "B.Fab")
		)
		(fp_line
			(start 0.299974 -0.150114)
			(end -0.299974 -0.150114)
			(stroke
				(width 0.1)
				(type default)
			)
			(layer "B.Fab")
		)
		(pad "1" smd rect
			(at 0.2667 0 90)
			(size 0.3048 0.381)
			(layers "B.Cu" "B.Mask" "B.Paste")
			(net "P0V9_CPU0_RT1_2A")
		)
		(pad "2" smd rect
			(at -0.2667 0 90)
			(size 0.3048 0.381)
			(layers "B.Cu" "B.Mask" "B.Paste")
			(net "GND")
		)
	)
	(footprint ""
		(layer "B.Cu")
		(at 298.565316 -425.288964)
		(property "Reference" "U49"
			(at 0.087884 -4.071366 0)
			(unlocked yes)
			(layer "B.SilkS")
			(effects
				(font
					(size 0.7874 0.5842)
					(thickness 0.1524)
				)
				(justify mirror)
			)
		)
		(property "Value" ""
			(at 0 0 0)
			(layer "B.Fab")
			(effects
				(font
					(size 1.27 1.27)
				)
				(justify mirror)
			)
		)
		(duplicate_pad_numbers_are_jumpers no)
		(fp_line
			(start -1.03378 -1.284478)
			(end -1.03378 1.284478)
			(stroke
				(width 0.1524)
				(type default)
			)
			(layer "B.SilkS")
		)
		(fp_line
			(start -1.03378 1.284478)
			(end 1.03378 1.284478)
			(stroke
				(width 0.1524)
				(type default)
			)
			(layer "B.SilkS")
		)
		(fp_line
			(start 1.03378 -1.284478)
			(end -1.03378 -1.284478)
			(stroke
				(width 0.1524)
				(type default)
			)
			(layer "B.SilkS")
		)
		(fp_line
			(start 1.03378 1.284478)
			(end 1.03378 -1.284478)
			(stroke
				(width 0.1524)
				(type default)
			)
			(layer "B.SilkS")
		)
		(fp_poly
			(pts
				(xy 1.201674 -0.750062) (xy 1.806702 -0.447548) (xy 1.806702 -1.052576)
			)
			(stroke
				(width 0)
				(type default)
			)
			(fill yes)
			(layer "B.SilkS")
		)
		(fp_line
			(start -0.774954 -1.02489)
			(end -0.774954 1.02489)
			(stroke
				(width 0.1)
				(type default)
			)
			(layer "B.Fab")
		)
		(fp_line
			(start -0.774954 1.02489)
			(end 0.774954 1.02489)
			(stroke
				(width 0.1)
				(type default)
			)
			(layer "B.Fab")
		)
		(fp_line
			(start 0.774954 -1.02489)
			(end -0.774954 -1.02489)
			(stroke
				(width 0.1)
				(type default)
			)
			(layer "B.Fab")
		)
		(fp_line
			(start 0.774954 1.02489)
			(end 0.774954 -1.02489)
			(stroke
				(width 0.1)
				(type default)
			)
			(layer "B.Fab")
		)
		(fp_poly
			(pts
				(xy 1.201674 -0.750062) (xy 1.806702 -0.447548) (xy 1.806702 -1.052576)
			)
			(stroke
				(width 0)
				(type default)
			)
			(fill yes)
			(layer "B.Fab")
		)
		(pad "1" smd rect
			(at 0.64008 -0.750062 90)
			(size 0.3048 0.5334)
			(layers "B.Cu" "B.Mask" "B.Paste")
			(net "SMB_RT_CPU0_P0_ROM_MUX_1D_SCL")
		)
		(pad "2" smd rect
			(at 0.64008 -0.249936 90)
			(size 0.254 0.5334)
			(layers "B.Cu" "B.Mask" "B.Paste")
			(net "SMB_RT_CPU0_P0_ROM_MUX_1D_SDA")
		)
		(pad "3" smd rect
			(at 0.64008 0.249936 90)
			(size 0.254 0.5334)
			(layers "B.Cu" "B.Mask" "B.Paste")
			(net "SMB_RT_CPU0_P0_ROM_MUX_2D_SCL")
		)
		(pad "4" smd rect
			(at 0.64008 0.750062 90)
			(size 0.3048 0.5334)
			(layers "B.Cu" "B.Mask" "B.Paste")
			(net "SMB_RT_CPU0_P0_ROM_MUX_2D_SDA")
		)
		(pad "5" smd rect
			(at 0 0.839978 180)
			(size 0.3302 0.635)
			(layers "B.Cu" "B.Mask" "B.Paste")
			(net "GND")
		)
		(pad "6" smd rect
			(at -0.64008 0.750062 90)
			(size 0.3048 0.5334)
			(layers "B.Cu" "B.Mask" "B.Paste")
			(net "RT_ROM_MUX5_OE_N")
		)
		(pad "7" smd rect
			(at -0.64008 0.249936 90)
			(size 0.254 0.5334)
			(layers "B.Cu" "B.Mask" "B.Paste")
			(net "SMB_RT_CPU0_P0_ROM_R_SDA")
		)
		(pad "8" smd rect
			(at -0.64008 -0.249936 90)
			(size 0.254 0.5334)
			(layers "B.Cu" "B.Mask" "B.Paste")
			(net "SMB_RT_CPU0_P0_ROM_R_SCL")
		)
		(pad "9" smd rect
			(at -0.64008 -0.750062 90)
			(size 0.3048 0.5334)
			(layers "B.Cu" "B.Mask" "B.Paste")
			(net "FM_SMB_RT_ROM_MUX5_SEL")
		)
		(pad "10" smd rect
			(at 0 -0.839978 180)
			(size 0.3302 0.635)
			(layers "B.Cu" "B.Mask" "B.Paste")
			(net "P3V3_AUX")
		)
	)
	(footprint ""
		(layer "B.Cu")
		(at 216.0905 -322.52539)
		(property "Reference" "R1268"
			(at 0 0 0)
			(layer "B.SilkS")
			(hide yes)
			(effects
				(font
					(size 1.27 1.27)
				)
				(justify mirror)
			)
		)
		(property "Value" ""
			(at 0 0 0)
			(layer "B.Fab")
			(effects
				(font
					(size 1.27 1.27)
				)
				(justify mirror)
			)
		)
		(duplicate_pad_numbers_are_jumpers no)
		(fp_line
			(start -0.7874 -0.4064)
			(end -0.7874 0.4064)
			(stroke
				(width 0.1524)
				(type default)
			)
			(layer "B.SilkS")
		)
		(fp_line
			(start -0.7874 0.4064)
			(end 0.7874 0.4064)
			(stroke
				(width 0.1524)
				(type default)
			)
			(layer "B.SilkS")
		)
		(fp_line
			(start 0.7874 -0.4064)
			(end -0.7874 -0.4064)
			(stroke
				(width 0.1524)
				(type default)
			)
			(layer "B.SilkS")
		)
		(fp_line
			(start 0.7874 0.4064)
			(end 0.7874 -0.4064)
			(stroke
				(width 0.1524)
				(type default)
			)
			(layer "B.SilkS")
		)
		(fp_line
			(start -0.67945 -0.3048)
			(end -0.67945 0.3048)
			(stroke
				(width 0.1)
				(type default)
			)
			(layer "B.Fab")
		)
		(fp_line
			(start -0.67945 0.3048)
			(end -0.120396 0.3048)
			(stroke
				(width 0.1)
				(type default)
			)
			(layer "B.Fab")
		)
		(fp_line
			(start -0.12065 -0.3048)
			(end -0.67945 -0.3048)
			(stroke
				(width 0.1)
				(type default)
			)
			(layer "B.Fab")
		)
		(fp_line
			(start -0.12065 -0.2794)
			(end -0.12065 -0.3048)
			(stroke
				(width 0.1)
				(type default)
			)
			(layer "B.Fab")
		)
		(fp_line
			(start -0.120396 0.2794)
			(end 0.12065 0.2794)
			(stroke
				(width 0.1)
				(type default)
			)
			(layer "B.Fab")
		)
		(fp_line
			(start -0.120396 0.3048)
			(end -0.120396 0.2794)
			(stroke
				(width 0.1)
				(type default)
			)
			(layer "B.Fab")
		)
		(fp_line
			(start 0.12065 -0.305054)
			(end 0.12065 -0.2794)
			(stroke
				(width 0.1)
				(type default)
			)
			(layer "B.Fab")
		)
		(fp_line
			(start 0.12065 -0.2794)
			(end -0.12065 -0.2794)
			(stroke
				(width 0.1)
				(type default)
			)
			(layer "B.Fab")
		)
		(fp_line
			(start 0.12065 0.2794)
			(end 0.12065 0.3048)
			(stroke
				(width 0.1)
				(type default)
			)
			(layer "B.Fab")
		)
		(fp_line
			(start 0.12065 0.3048)
			(end 0.67945 0.3048)
			(stroke
				(width 0.1)
				(type default)
			)
			(layer "B.Fab")
		)
		(fp_line
			(start 0.67945 -0.305054)
			(end 0.12065 -0.305054)
			(stroke
				(width 0.1)
				(type default)
			)
			(layer "B.Fab")
		)
		(fp_line
			(start 0.67945 0.3048)
			(end 0.67945 -0.305054)
			(stroke
				(width 0.1)
				(type default)
			)
			(layer "B.Fab")
		)
		(pad "1" smd circle
			(at 0.40005 0 180)
			(size 0 0)
			(layers "B.Cu" "B.Mask" "B.Paste")
			(net "ADC128_2_VREF")
		)
		(pad "2" smd circle
			(at -0.40005 0 180)
			(size 0 0)
			(layers "B.Cu" "B.Mask" "B.Paste")
			(net "GND")
		)
	)
)
